FILE_TYPE = MULTI_PHYS_TABLE;
PART 'TTL08'
{====================================================================================================================================================================================}
:VALUE    | PACK_TYPE | MATERIAL | PART_NUMBER     = EnvComp | PART_NUMBER  | JEDEC_TYPE       | CLASS | DESCRIPTION                              | HEIGHT    | COMPONENT_TYPE | LPID  | SPEED_URL | Status |RPL| AML | Bus_Unit | Days ;
{====================================================================================================================================================================================}
'74LVC08A'| 'QFN15'   | 'IC'     | 'D90404-001'(!) = 'YES;YES;YES;UNK;ok;VLD' | 'D90404-001' | 'QFN14_14_14_5MB'| 'IC'  | '(USE SYM_2 OR SYM_4) QUAD AND'          | '0.039 IN' | 'LCC'          | '1642' | 'http://speed.intel.com:8081/speed/module/pdm/item/pdm_item_detail_direct.asp?item_cde=D90404-001&item_rev=01&url_param=unused' | 'Conditional' | 'YES' | '2' | 'SMO_IC' | '84' 
'74LVC08A'| 'QFN15'   | 'EMPTY'  | 'D90404-001'(!) = 'YES;YES;YES;UNK;ok;VLD' | 'D90404-001' | 'QFN14_14_14_5MB'| 'IO'  | '(USE SYM_2 OR SYM_4) QUAD AND'          | '0.039 IN' | 'LCC'          | '1642' | 'http://speed.intel.com:8081/speed/module/pdm/item/pdm_item_detail_direct.asp?item_cde=D90404-001&item_rev=01&url_param=unused' | 'Conditional' | 'YES' | '2' | 'SMO_IC' | '84' 
END_PART
END.
